# S9S_MB_2U (Grand Teton) — schematic netlist excerpt (pin names and nets, part order shuffled) for the footprints in the layout excerpt that follows; sources: Cadence DE-HDL packaged netlist, KiCad conversion of 03242023_DA0F0TMBIJ0_F0T_Motherboard_J_brd_V01_OCP.brd

R2898  Q_RES  33.2 1% CHIP  pkg 0402LF  page 234 : A = SMB_1_BMC_GPU_BUF_R_SDA ; B = SMB_1_BMC_GPU_BUF_SDA
R1690  Q_RES  10K 1% CHIP  pkg 0402LF  page 244 : A = P3V3_AUX ; B = FM_COMP_P3V3_AUX_ENIN

(kicad_pcb
	(version 20260206)
	(generator "pcbnew")
	(generator_version "10.0")
	(general
		(thickness 1.6)
		(legacy_teardrops no)
	)
	(paper "A4")
	(title_block
		(title "03242023_DA0F0TMBIJ0_F0T_Motherboard_J_brd_V01_OCP.brd")
		(comment 1 "Grand Teton / footprints 1404-1405 of 6105")
	)
	(layers
		(0 "F.Cu" signal "TOP")
		(4 "In1.Cu" signal "GND")
		(6 "In2.Cu" signal "IN1")
		(8 "In3.Cu" signal "GND1")
		(10 "In4.Cu" signal "IN2")
		(12 "In5.Cu" signal "GND2")
		(14 "In6.Cu" signal "IN3")
		(16 "In7.Cu" signal "GND3")
		(18 "In8.Cu" signal "VCC")
		(20 "In9.Cu" signal "VCC1")
		(22 "In10.Cu" signal "GND4")
		(24 "In11.Cu" signal "IN4")
		(26 "In12.Cu" signal "GND5")
		(28 "In13.Cu" signal "IN5")
		(30 "In14.Cu" signal "GND6")
		(32 "In15.Cu" signal "IN6")
		(34 "In16.Cu" signal "GND7")
		(2 "B.Cu" signal "BOTTOM")
		(9 "F.Adhes" user "F.Adhesive")
		(11 "B.Adhes" user "B.Adhesive")
		(13 "F.Paste" user "Package Geometry/Pastemask Top")
		(15 "B.Paste" user "Package Geometry/Pastemask Bottom")
		(5 "F.SilkS" user "Ref Des/Silkscreen Top")
		(7 "B.SilkS" user "Ref Des/Silkscreen Bottom")
		(1 "F.Mask" user "Board Geometry/Soldermask Top")
		(3 "B.Mask" user "Board Geometry/Soldermask Bottom")
		(17 "Dwgs.User" user "User.Drawings")
		(19 "Cmts.User" user "User.Comments")
		(21 "Eco1.User" user "User.Eco1")
		(23 "Eco2.User" user "User.Eco2")
		(25 "Edge.Cuts" user "Board Geometry/Outline")
		(27 "Margin" user)
		(31 "F.CrtYd" user "Package Geometry/Place Bound Top")
		(29 "B.CrtYd" user "Package Geometry/Place Bound Bottom")
		(35 "F.Fab" user "Ref Des/Assembly Top")
		(33 "B.Fab" user "Ref Des/Assembly Bottom")
	)
	(footprint ""
		(layer "F.Cu")
		(at 209.74558 -132.862828)
		(property "Reference" "R1690"
			(at 0 0 0)
			(layer "F.SilkS")
			(hide yes)
			(effects
				(font
					(size 1.27 1.27)
				)
			)
		)
		(property "Value" ""
			(at 0 0 0)
			(layer "F.Fab")
			(effects
				(font
					(size 1.27 1.27)
				)
			)
		)
		(duplicate_pad_numbers_are_jumpers no)
		(fp_line
			(start -0.7874 -0.4064)
			(end 0.7874 -0.4064)
			(stroke
				(width 0.1524)
				(type default)
			)
			(layer "F.SilkS")
		)
		(fp_line
			(start -0.7874 0.4064)
			(end -0.7874 -0.4064)
			(stroke
				(width 0.1524)
				(type default)
			)
			(layer "F.SilkS")
		)
		(fp_line
			(start 0.7874 -0.4064)
			(end 0.7874 0.4064)
			(stroke
				(width 0.1524)
				(type default)
			)
			(layer "F.SilkS")
		)
		(fp_line
			(start 0.7874 0.4064)
			(end -0.7874 0.4064)
			(stroke
				(width 0.1524)
				(type default)
			)
			(layer "F.SilkS")
		)
		(fp_line
			(start -0.67945 -0.305054)
			(end -0.12065 -0.305054)
			(stroke
				(width 0.1)
				(type default)
			)
			(layer "F.Fab")
		)
		(fp_line
			(start -0.67945 0.3048)
			(end -0.67945 -0.305054)
			(stroke
				(width 0.1)
				(type default)
			)
			(layer "F.Fab")
		)
		(fp_line
			(start -0.12065 -0.305054)
			(end -0.12065 -0.2794)
			(stroke
				(width 0.1)
				(type default)
			)
			(layer "F.Fab")
		)
		(fp_line
			(start -0.12065 -0.2794)
			(end 0.12065 -0.2794)
			(stroke
				(width 0.1)
				(type default)
			)
			(layer "F.Fab")
		)
		(fp_line
			(start -0.12065 0.2794)
			(end -0.12065 0.3048)
			(stroke
				(width 0.1)
				(type default)
			)
			(layer "F.Fab")
		)
		(fp_line
			(start -0.12065 0.3048)
			(end -0.67945 0.3048)
			(stroke
				(width 0.1)
				(type default)
			)
			(layer "F.Fab")
		)
		(fp_line
			(start 0.120396 0.2794)
			(end -0.12065 0.2794)
			(stroke
				(width 0.1)
				(type default)
			)
			(layer "F.Fab")
		)
		(fp_line
			(start 0.120396 0.3048)
			(end 0.120396 0.2794)
			(stroke
				(width 0.1)
				(type default)
			)
			(layer "F.Fab")
		)
		(fp_line
			(start 0.12065 -0.3048)
			(end 0.67945 -0.3048)
			(stroke
				(width 0.1)
				(type default)
			)
			(layer "F.Fab")
		)
		(fp_line
			(start 0.12065 -0.2794)
			(end 0.12065 -0.3048)
			(stroke
				(width 0.1)
				(type default)
			)
			(layer "F.Fab")
		)
		(fp_line
			(start 0.67945 -0.3048)
			(end 0.67945 0.3048)
			(stroke
				(width 0.1)
				(type default)
			)
			(layer "F.Fab")
		)
		(fp_line
			(start 0.67945 0.3048)
			(end 0.120396 0.3048)
			(stroke
				(width 0.1)
				(type default)
			)
			(layer "F.Fab")
		)
		(pad "1" smd circle
			(at -0.40005 0)
			(size 0 0)
			(layers "F.Cu" "F.Mask" "F.Paste")
			(net "P3V3_AUX")
		)
		(pad "2" smd circle
			(at 0.40005 0)
			(size 0 0)
			(layers "F.Cu" "F.Mask" "F.Paste")
			(net "FM_COMP_P3V3_AUX_ENIN")
		)
	)
	(footprint ""
		(layer "F.Cu")
		(at 52.480972 -436.376318)
		(property "Reference" "R2898"
			(at 0 0 0)
			(layer "F.SilkS")
			(hide yes)
			(effects
				(font
					(size 1.27 1.27)
				)
			)
		)
		(property "Value" ""
			(at 0 0 0)
			(layer "F.Fab")
			(effects
				(font
					(size 1.27 1.27)
				)
			)
		)
		(duplicate_pad_numbers_are_jumpers no)
		(fp_line
			(start -0.7874 -0.4064)
			(end 0.7874 -0.4064)
			(stroke
				(width 0.1524)
				(type default)
			)
			(layer "F.SilkS")
		)
		(fp_line
			(start -0.7874 0.4064)
			(end -0.7874 -0.4064)
			(stroke
				(width 0.1524)
				(type default)
			)
			(layer "F.SilkS")
		)
		(fp_line
			(start 0.7874 -0.4064)
			(end 0.7874 0.4064)
			(stroke
				(width 0.1524)
				(type default)
			)
			(layer "F.SilkS")
		)
		(fp_line
			(start 0.7874 0.4064)
			(end -0.7874 0.4064)
			(stroke
				(width 0.1524)
				(type default)
			)
			(layer "F.SilkS")
		)
		(fp_line
			(start -0.67945 -0.305054)
			(end -0.12065 -0.305054)
			(stroke
				(width 0.1)
				(type default)
			)
			(layer "F.Fab")
		)
		(fp_line
			(start -0.67945 0.3048)
			(end -0.67945 -0.305054)
			(stroke
				(width 0.1)
				(type default)
			)
			(layer "F.Fab")
		)
		(fp_line
			(start -0.12065 -0.305054)
			(end -0.12065 -0.2794)
			(stroke
				(width 0.1)
				(type default)
			)
			(layer "F.Fab")
		)
		(fp_line
			(start -0.12065 -0.2794)
			(end 0.12065 -0.2794)
			(stroke
				(width 0.1)
				(type default)
			)
			(layer "F.Fab")
		)
		(fp_line
			(start -0.12065 0.2794)
			(end -0.12065 0.3048)
			(stroke
				(width 0.1)
				(type default)
			)
			(layer "F.Fab")
		)
		(fp_line
			(start -0.12065 0.3048)
			(end -0.67945 0.3048)
			(stroke
				(width 0.1)
				(type default)
			)
			(layer "F.Fab")
		)
		(fp_line
			(start 0.120396 0.2794)
			(end -0.12065 0.2794)
			(stroke
				(width 0.1)
				(type default)
			)
			(layer "F.Fab")
		)
		(fp_line
			(start 0.120396 0.3048)
			(end 0.120396 0.2794)
			(stroke
				(width 0.1)
				(type default)
			)
			(layer "F.Fab")
		)
		(fp_line
			(start 0.12065 -0.3048)
			(end 0.67945 -0.3048)
			(stroke
				(width 0.1)
				(type default)
			)
			(layer "F.Fab")
		)
		(fp_line
			(start 0.12065 -0.2794)
			(end 0.12065 -0.3048)
			(stroke
				(width 0.1)
				(type default)
			)
			(layer "F.Fab")
		)
		(fp_line
			(start 0.67945 -0.3048)
			(end 0.67945 0.3048)
			(stroke
				(width 0.1)
				(type default)
			)
			(layer "F.Fab")
		)
		(fp_line
			(start 0.67945 0.3048)
			(end 0.120396 0.3048)
			(stroke
				(width 0.1)
				(type default)
			)
			(layer "F.Fab")
		)
		(pad "1" smd circle
			(at -0.40005 0)
			(size 0 0)
			(layers "F.Cu" "F.Mask" "F.Paste")
			(net "SMB_1_BMC_GPU_BUF_R_SDA")
		)
		(pad "2" smd circle
			(at 0.40005 0)
			(size 0 0)
			(layers "F.Cu" "F.Mask" "F.Paste")
			(net "SMB_1_BMC_GPU_BUF_SDA")
		)
	)
)
